(kicad_pcb
	(version 20260206)
	(generator "pcbnew")
	(generator_version "10.0")
	(general
		(thickness 1.6)
		(legacy_teardrops no)
	)
	(paper "A4")
	(title_block
		(title "panther-plus-userver — 13130-1b_20150205.brd")
		(comment 1 "Honey Badger (Wiwynn) / footprints 1119-1126 of 1509")
	)
	(layers
		(0 "F.Cu" signal "TOP")
		(4 "In1.Cu" signal "L2")
		(6 "In2.Cu" signal "L3")
		(8 "In3.Cu" signal "L4")
		(10 "In4.Cu" signal "L5")
		(12 "In5.Cu" signal "L6")
		(14 "In6.Cu" signal "L7")
		(16 "In7.Cu" signal "L8")
		(18 "In8.Cu" signal "L9")
		(20 "In9.Cu" signal "L10")
		(22 "In10.Cu" signal "L11")
		(2 "B.Cu" signal "BOTTOM")
		(9 "F.Adhes" user "F.Adhesive")
		(11 "B.Adhes" user "B.Adhesive")
		(13 "F.Paste" user "Package Geometry/Pastemask Top")
		(15 "B.Paste" user "Package Geometry/Pastemask Bottom")
		(5 "F.SilkS" user "Ref Des/Silkscreen Top")
		(7 "B.SilkS" user "Ref Des/Silkscreen Bottom")
		(1 "F.Mask" user "Board Geometry/Soldermask Top")
		(3 "B.Mask" user "Board Geometry/Soldermask Bottom")
		(17 "Dwgs.User" user "User.Drawings")
		(19 "Cmts.User" user "User.Comments")
		(21 "Eco1.User" user "User.Eco1")
		(23 "Eco2.User" user "User.Eco2")
		(25 "Edge.Cuts" user "Board Geometry/Outline")
		(27 "Margin" user)
		(31 "F.CrtYd" user "Package Geometry/Place Bound Top")
		(29 "B.CrtYd" user "Package Geometry/Place Bound Bottom")
		(35 "F.Fab" user "Ref Des/Assembly Top")
		(33 "B.Fab" user "Ref Des/Assembly Bottom")
	)
	(footprint ""
		(layer "B.Cu")
		(at 197.4596 -62.0522 -90)
		(property "Reference" "PC156"
			(at 0 0 90)
			(layer "B.SilkS")
			(hide yes)
			(effects
				(font
					(size 1.27 1.27)
				)
				(justify mirror)
			)
		)
		(property "Value" "SC10U6D3V3MX-GP"
			(at 0.0254 -2.0193 270)
			(unlocked yes)
			(layer "B.Fab")
			(hide yes)
			(effects
				(font
					(size 1.016 1.016)
					(thickness 0.1524)
				)
				(justify mirror)
			)
		)
		(property "Device Type" "C603H38"
			(at 0.0254 -3.5433 270)
			(unlocked yes)
			(layer "B.Fab")
			(hide yes)
			(effects
				(font
					(size 1.016 1.016)
					(thickness 0.1524)
				)
				(justify mirror)
			)
		)
		(duplicate_pad_numbers_are_jumpers no)
		(fp_line
			(start 0.4064 0)
			(end -0.4064 0)
			(stroke
				(width 0.2286)
				(type default)
			)
			(layer "B.SilkS")
		)
		(fp_rect
			(start 0.635 1.1811)
			(end -0.635 -1.1811)
			(stroke
				(width 0)
				(type default)
			)
			(fill no)
			(layer "B.CrtYd")
		)
		(fp_rect
			(start 0.635 1.1811)
			(end -0.635 -1.1811)
			(stroke
				(width 0)
				(type default)
			)
			(fill no)
			(layer "B.Fab")
		)
		(pad "1" smd custom
			(at 0 -0.6604 90)
			(size 0.19685 0.19685)
			(layers "B.Cu" "B.Mask" "B.Paste")
			(net "PV_VDDR")
			(options
				(clearance outline)
				(anchor circle)
			)
			(primitives
				(gr_poly
					(pts
						(arc
							(start 0.508 0.2921)
							(mid 0.478242 0.363942)
							(end 0.4064 0.3937)
						)
						(arc
							(start -0.4064 0.3937)
							(mid -0.478242 0.363942)
							(end -0.508 0.2921)
						)
						(arc
							(start -0.508 -0.2921)
							(mid -0.478242 -0.363942)
							(end -0.4064 -0.3937)
						)
						(arc
							(start 0.4064 -0.3937)
							(mid 0.478242 -0.363942)
							(end 0.508 -0.2921)
						)
					)
					(width 0)
					(fill yes)
				)
			)
		)
		(pad "2" smd custom
			(at 0 0.6604 90)
			(size 0.19685 0.19685)
			(layers "B.Cu" "B.Mask" "B.Paste")
			(net "GND")
			(options
				(clearance outline)
				(anchor circle)
			)
			(primitives
				(gr_poly
					(pts
						(arc
							(start 0.508 0.2921)
							(mid 0.478242 0.363942)
							(end 0.4064 0.3937)
						)
						(arc
							(start -0.4064 0.3937)
							(mid -0.478242 0.363942)
							(end -0.508 0.2921)
						)
						(arc
							(start -0.508 -0.2921)
							(mid -0.478242 -0.363942)
							(end -0.4064 -0.3937)
						)
						(arc
							(start 0.4064 -0.3937)
							(mid 0.478242 -0.363942)
							(end 0.508 -0.2921)
						)
					)
					(width 0)
					(fill yes)
				)
			)
		)
	)
	(footprint ""
		(layer "B.Cu")
		(at 91.186 -43.053 180)
		(property "Reference" "C152"
			(at 0 0 0)
			(layer "B.SilkS")
			(hide yes)
			(effects
				(font
					(size 1.27 1.27)
				)
				(justify mirror)
			)
		)
		(property "Value" "SC1U10V2KX-1GP"
			(at -1.1811 -2.7051 180)
			(unlocked yes)
			(layer "B.Fab")
			(hide yes)
			(effects
				(font
					(size 1.016 1.016)
					(thickness 0.1524)
				)
				(justify mirror)
			)
		)
		(property "Device Type" "C402H22"
			(at -1.1811 -4.2291 180)
			(unlocked yes)
			(layer "B.Fab")
			(hide yes)
			(effects
				(font
					(size 1.016 1.016)
					(thickness 0.1524)
				)
				(justify mirror)
			)
		)
		(duplicate_pad_numbers_are_jumpers no)
		(fp_rect
			(start 0.381 0.7366)
			(end -0.381 -0.7366)
			(stroke
				(width 0)
				(type default)
			)
			(fill no)
			(layer "B.CrtYd")
		)
		(fp_rect
			(start 0.381 0.7366)
			(end -0.381 -0.7366)
			(stroke
				(width 0)
				(type default)
			)
			(fill no)
			(layer "B.Fab")
		)
		(pad "1" smd custom
			(at 0 -0.4572)
			(size 0.1143 0.1143)
			(layers "B.Cu" "B.Mask" "B.Paste")
			(net "P1V0_STBY")
			(options
				(clearance outline)
				(anchor circle)
			)
			(primitives
				(gr_poly
					(pts
						(arc
							(start -0.254 0.1778)
							(mid -0.239121 0.213721)
							(end -0.2032 0.2286)
						)
						(arc
							(start 0.2032 0.2286)
							(mid 0.239121 0.213721)
							(end 0.254 0.1778)
						)
						(arc
							(start 0.254 -0.1778)
							(mid 0.239121 -0.213721)
							(end 0.2032 -0.2286)
						)
						(arc
							(start -0.2032 -0.2286)
							(mid -0.239121 -0.213721)
							(end -0.254 -0.1778)
						)
					)
					(width 0)
					(fill yes)
				)
			)
		)
		(pad "2" smd custom
			(at 0 0.4572)
			(size 0.1143 0.1143)
			(layers "B.Cu" "B.Mask" "B.Paste")
			(net "GND")
			(options
				(clearance outline)
				(anchor circle)
			)
			(primitives
				(gr_poly
					(pts
						(arc
							(start -0.254 0.1778)
							(mid -0.239121 0.213721)
							(end -0.2032 0.2286)
						)
						(arc
							(start 0.2032 0.2286)
							(mid 0.239121 0.213721)
							(end 0.254 0.1778)
						)
						(arc
							(start 0.254 -0.1778)
							(mid 0.239121 -0.213721)
							(end 0.2032 -0.2286)
						)
						(arc
							(start -0.2032 -0.2286)
							(mid -0.239121 -0.213721)
							(end -0.254 -0.1778)
						)
					)
					(width 0)
					(fill yes)
				)
			)
		)
	)
	(footprint ""
		(layer "B.Cu")
		(at 197.739 -1.651 90)
		(property "Reference" "C292"
			(at 0 0 90)
			(layer "B.SilkS")
			(hide yes)
			(effects
				(font
					(size 1.27 1.27)
				)
				(justify mirror)
			)
		)
		(property "Value" "SC10U6D3V3MX-GP"
			(at 0 -2.8194 90)
			(unlocked yes)
			(layer "B.Fab")
			(hide yes)
			(effects
				(font
					(size 1.016 1.016)
					(thickness 0.1524)
				)
				(justify mirror)
			)
		)
		(property "Device Type" "C603H38"
			(at 0 -4.3434 90)
			(unlocked yes)
			(layer "B.Fab")
			(hide yes)
			(effects
				(font
					(size 1.016 1.016)
					(thickness 0.1524)
				)
				(justify mirror)
			)
		)
		(duplicate_pad_numbers_are_jumpers no)
		(fp_line
			(start 0.4064 0)
			(end -0.4064 0)
			(stroke
				(width 0.2286)
				(type default)
			)
			(layer "B.SilkS")
		)
		(fp_rect
			(start 0.635 1.1811)
			(end -0.635 -1.1811)
			(stroke
				(width 0)
				(type default)
			)
			(fill no)
			(layer "B.CrtYd")
		)
		(fp_rect
			(start 0.635 1.1811)
			(end -0.635 -1.1811)
			(stroke
				(width 0)
				(type default)
			)
			(fill no)
			(layer "B.Fab")
		)
		(pad "1" smd custom
			(at 0 -0.6604 270)
			(size 0.19685 0.19685)
			(layers "B.Cu" "B.Mask" "B.Paste")
			(net "PV_VTT_DDR_B")
			(options
				(clearance outline)
				(anchor circle)
			)
			(primitives
				(gr_poly
					(pts
						(arc
							(start 0.508 0.2921)
							(mid 0.478242 0.363942)
							(end 0.4064 0.3937)
						)
						(arc
							(start -0.4064 0.3937)
							(mid -0.478242 0.363942)
							(end -0.508 0.2921)
						)
						(arc
							(start -0.508 -0.2921)
							(mid -0.478242 -0.363942)
							(end -0.4064 -0.3937)
						)
						(arc
							(start 0.4064 -0.3937)
							(mid 0.478242 -0.363942)
							(end 0.508 -0.2921)
						)
					)
					(width 0)
					(fill yes)
				)
			)
		)
		(pad "2" smd custom
			(at 0 0.6604 270)
			(size 0.19685 0.19685)
			(layers "B.Cu" "B.Mask" "B.Paste")
			(net "GND")
			(options
				(clearance outline)
				(anchor circle)
			)
			(primitives
				(gr_poly
					(pts
						(arc
							(start 0.508 0.2921)
							(mid 0.478242 0.363942)
							(end 0.4064 0.3937)
						)
						(arc
							(start -0.4064 0.3937)
							(mid -0.478242 0.363942)
							(end -0.508 0.2921)
						)
						(arc
							(start -0.508 -0.2921)
							(mid -0.478242 -0.363942)
							(end -0.4064 -0.3937)
						)
						(arc
							(start 0.4064 -0.3937)
							(mid 0.478242 -0.363942)
							(end 0.508 -0.2921)
						)
					)
					(width 0)
					(fill yes)
				)
			)
		)
	)
	(footprint ""
		(layer "B.Cu")
		(at 128.778 -56.388)
		(property "Reference" "C112"
			(at 0 0 0)
			(layer "B.SilkS")
			(hide yes)
			(effects
				(font
					(size 1.27 1.27)
				)
				(justify mirror)
			)
		)
		(property "Value" "SC10U6D3V3MX-GP"
			(at 0 -2.8194 0)
			(unlocked yes)
			(layer "B.Fab")
			(hide yes)
			(effects
				(font
					(size 1.016 1.016)
					(thickness 0.1524)
				)
				(justify mirror)
			)
		)
		(property "Device Type" "C603H38"
			(at 0 -4.3434 0)
			(unlocked yes)
			(layer "B.Fab")
			(hide yes)
			(effects
				(font
					(size 1.016 1.016)
					(thickness 0.1524)
				)
				(justify mirror)
			)
		)
		(duplicate_pad_numbers_are_jumpers no)
		(fp_line
			(start 0.4064 0)
			(end -0.4064 0)
			(stroke
				(width 0.2286)
				(type default)
			)
			(layer "B.SilkS")
		)
		(fp_rect
			(start 0.635 1.1811)
			(end -0.635 -1.1811)
			(stroke
				(width 0)
				(type default)
			)
			(fill no)
			(layer "B.CrtYd")
		)
		(fp_rect
			(start 0.635 1.1811)
			(end -0.635 -1.1811)
			(stroke
				(width 0)
				(type default)
			)
			(fill no)
			(layer "B.Fab")
		)
		(pad "1" smd custom
			(at 0 -0.6604 180)
			(size 0.19685 0.19685)
			(layers "B.Cu" "B.Mask" "B.Paste")
			(net "PV_VTT_DDR_A")
			(options
				(clearance outline)
				(anchor circle)
			)
			(primitives
				(gr_poly
					(pts
						(arc
							(start 0.508 0.2921)
							(mid 0.478242 0.363942)
							(end 0.4064 0.3937)
						)
						(arc
							(start -0.4064 0.3937)
							(mid -0.478242 0.363942)
							(end -0.508 0.2921)
						)
						(arc
							(start -0.508 -0.2921)
							(mid -0.478242 -0.363942)
							(end -0.4064 -0.3937)
						)
						(arc
							(start 0.4064 -0.3937)
							(mid 0.478242 -0.363942)
							(end 0.508 -0.2921)
						)
					)
					(width 0)
					(fill yes)
				)
			)
		)
		(pad "2" smd custom
			(at 0 0.6604 180)
			(size 0.19685 0.19685)
			(layers "B.Cu" "B.Mask" "B.Paste")
			(net "GND")
			(options
				(clearance outline)
				(anchor circle)
			)
			(primitives
				(gr_poly
					(pts
						(arc
							(start 0.508 0.2921)
							(mid 0.478242 0.363942)
							(end 0.4064 0.3937)
						)
						(arc
							(start -0.4064 0.3937)
							(mid -0.478242 0.363942)
							(end -0.508 0.2921)
						)
						(arc
							(start -0.508 -0.2921)
							(mid -0.478242 -0.363942)
							(end -0.4064 -0.3937)
						)
						(arc
							(start 0.4064 -0.3937)
							(mid 0.478242 -0.363942)
							(end 0.508 -0.2921)
						)
					)
					(width 0)
					(fill yes)
				)
			)
		)
	)
	(footprint ""
		(layer "B.Cu")
		(at 16.764 -33.655 -90)
		(property "Reference" "PC151"
			(at 0 0 90)
			(layer "B.SilkS")
			(hide yes)
			(effects
				(font
					(size 1.27 1.27)
				)
				(justify mirror)
			)
		)
		(property "Value" "SC1U10V2KX-1GP"
			(at -1.8923 -1.2065 270)
			(unlocked yes)
			(layer "B.Fab")
			(hide yes)
			(effects
				(font
					(size 1.016 1.016)
					(thickness 0.1524)
				)
				(justify mirror)
			)
		)
		(property "Device Type" "C402H22"
			(at -1.8923 -2.7305 270)
			(unlocked yes)
			(layer "B.Fab")
			(hide yes)
			(effects
				(font
					(size 1.016 1.016)
					(thickness 0.1524)
				)
				(justify mirror)
			)
		)
		(duplicate_pad_numbers_are_jumpers no)
		(fp_rect
			(start 0.381 0.7366)
			(end -0.381 -0.7366)
			(stroke
				(width 0)
				(type default)
			)
			(fill no)
			(layer "B.CrtYd")
		)
		(fp_rect
			(start 0.381 0.7366)
			(end -0.381 -0.7366)
			(stroke
				(width 0)
				(type default)
			)
			(fill no)
			(layer "B.Fab")
		)
		(pad "1" smd custom
			(at 0 -0.4572 90)
			(size 0.1143 0.1143)
			(layers "B.Cu" "B.Mask" "B.Paste")
			(net "AGND_P3V3_STBY")
			(options
				(clearance outline)
				(anchor circle)
			)
			(primitives
				(gr_poly
					(pts
						(arc
							(start -0.254 0.1778)
							(mid -0.239121 0.213721)
							(end -0.2032 0.2286)
						)
						(arc
							(start 0.2032 0.2286)
							(mid 0.239121 0.213721)
							(end 0.254 0.1778)
						)
						(arc
							(start 0.254 -0.1778)
							(mid 0.239121 -0.213721)
							(end 0.2032 -0.2286)
						)
						(arc
							(start -0.2032 -0.2286)
							(mid -0.239121 -0.213721)
							(end -0.254 -0.1778)
						)
					)
					(width 0)
					(fill yes)
				)
			)
		)
		(pad "2" smd custom
			(at 0 0.4572 90)
			(size 0.1143 0.1143)
			(layers "B.Cu" "B.Mask" "B.Paste")
			(net "P3V3_STBY_ROVP")
			(options
				(clearance outline)
				(anchor circle)
			)
			(primitives
				(gr_poly
					(pts
						(arc
							(start -0.254 0.1778)
							(mid -0.239121 0.213721)
							(end -0.2032 0.2286)
						)
						(arc
							(start 0.2032 0.2286)
							(mid 0.239121 0.213721)
							(end 0.254 0.1778)
						)
						(arc
							(start 0.254 -0.1778)
							(mid 0.239121 -0.213721)
							(end 0.2032 -0.2286)
						)
						(arc
							(start -0.2032 -0.2286)
							(mid -0.239121 -0.213721)
							(end -0.254 -0.1778)
						)
					)
					(width 0)
					(fill yes)
				)
			)
		)
	)
	(footprint ""
		(layer "B.Cu")
		(at 70.8406 -15.4686 90)
		(property "Reference" "PC124"
			(at 0 0 90)
			(layer "B.SilkS")
			(hide yes)
			(effects
				(font
					(size 1.27 1.27)
				)
				(justify mirror)
			)
		)
		(property "Value" "SC22U6D3V5MX-2GP"
			(at 0 -4.9022 90)
			(unlocked yes)
			(layer "B.Fab")
			(hide yes)
			(effects
				(font
					(size 1.016 1.016)
					(thickness 0.1524)
				)
				(justify mirror)
			)
		)
		(property "Device Type" "C805H58"
			(at 0 -6.8072 90)
			(unlocked yes)
			(layer "B.Fab")
			(hide yes)
			(effects
				(font
					(size 1.016 1.016)
					(thickness 0.1524)
				)
				(justify mirror)
			)
		)
		(duplicate_pad_numbers_are_jumpers no)
		(fp_line
			(start -0.6096 0)
			(end 0.6096 0)
			(stroke
				(width 0.3048)
				(type default)
			)
			(layer "B.SilkS")
		)
		(fp_poly
			(pts
				(xy 0.9017 1.4351) (xy -0.9017 1.4351) (xy -0.9017 -1.4351) (xy 0.9017 -1.4351)
			)
			(stroke
				(width 0)
				(type default)
			)
			(fill no)
			(layer "B.CrtYd")
		)
		(fp_poly
			(pts
				(xy -0.9017 1.4351) (xy -0.9017 -1.4351) (xy 0.9017 -1.4351) (xy 0.9017 1.4351)
			)
			(stroke
				(width 0)
				(type default)
			)
			(fill no)
			(layer "B.Fab")
		)
		(pad "1" smd rect
			(at 0 -0.8382 270)
			(size 1.5494 0.9398)
			(layers "B.Cu" "B.Mask" "B.Paste")
			(net "P1V8_STBY_VOUT")
		)
		(pad "2" smd rect
			(at 0 0.8382 270)
			(size 1.5494 0.9398)
			(layers "B.Cu" "B.Mask" "B.Paste")
			(net "GND")
		)
	)
	(footprint ""
		(layer "B.Cu")
		(at 197.231 -66.04 90)
		(property "Reference" "R400"
			(at 0 0 90)
			(layer "B.SilkS")
			(hide yes)
			(effects
				(font
					(size 1.27 1.27)
				)
				(justify mirror)
			)
		)
		(property "Value" "300R2F-GP"
			(at -1.7907 -1.1176 90)
			(unlocked yes)
			(layer "B.Fab")
			(hide yes)
			(effects
				(font
					(size 1.016 1.016)
					(thickness 0.1524)
				)
				(justify mirror)
			)
		)
		(property "Device Type" "R402H16"
			(at -1.7907 -2.6416 90)
			(unlocked yes)
			(layer "B.Fab")
			(hide yes)
			(effects
				(font
					(size 1.016 1.016)
					(thickness 0.1524)
				)
				(justify mirror)
			)
		)
		(duplicate_pad_numbers_are_jumpers no)
		(fp_rect
			(start 0.381 0.8382)
			(end -0.381 -0.8382)
			(stroke
				(width 0)
				(type default)
			)
			(fill no)
			(layer "B.CrtYd")
		)
		(fp_rect
			(start 0.381 0.8382)
			(end -0.381 -0.8382)
			(stroke
				(width 0)
				(type default)
			)
			(fill no)
			(layer "B.Fab")
		)
		(pad "1" smd custom
			(at 0 -0.4318 270)
			(size 0.127 0.127)
			(layers "B.Cu" "B.Mask" "B.Paste")
			(net "P3V3")
			(options
				(clearance outline)
				(anchor circle)
			)
			(primitives
				(gr_poly
					(pts
						(arc
							(start -0.2032 0.2794)
							(mid -0.239121 0.264521)
							(end -0.254 0.2286)
						)
						(arc
							(start -0.254 -0.2286)
							(mid -0.239121 -0.264521)
							(end -0.2032 -0.2794)
						)
						(arc
							(start 0.2032 -0.2794)
							(mid 0.239121 -0.264521)
							(end 0.254 -0.2286)
						)
						(arc
							(start 0.254 0.2286)
							(mid 0.239121 0.264521)
							(end 0.2032 0.2794)
						)
					)
					(width 0)
					(fill yes)
				)
			)
		)
		(pad "2" smd custom
			(at 0 0.4318 270)
			(size 0.127 0.127)
			(layers "B.Cu" "B.Mask" "B.Paste")
			(net "DIAG_LED")
			(options
				(clearance outline)
				(anchor circle)
			)
			(primitives
				(gr_poly
					(pts
						(arc
							(start -0.2032 0.2794)
							(mid -0.239121 0.264521)
							(end -0.254 0.2286)
						)
						(arc
							(start -0.254 -0.2286)
							(mid -0.239121 -0.264521)
							(end -0.2032 -0.2794)
						)
						(arc
							(start 0.2032 -0.2794)
							(mid 0.239121 -0.264521)
							(end 0.254 -0.2286)
						)
						(arc
							(start 0.254 0.2286)
							(mid 0.239121 0.264521)
							(end 0.2032 0.2794)
						)
					)
					(width 0)
					(fill yes)
				)
			)
		)
	)
	(footprint ""
		(layer "B.Cu")
		(at 197.358 -38.6588 180)
		(property "Reference" "PC111"
			(at 0 0 0)
			(layer "B.SilkS")
			(hide yes)
			(effects
				(font
					(size 1.27 1.27)
				)
				(justify mirror)
			)
		)
		(property "Value" "SC10U16V6KX-2GP"
			(at -0.0127 -3.4671 180)
			(unlocked yes)
			(layer "B.Fab")
			(hide yes)
			(effects
				(font
					(size 1.016 1.016)
					(thickness 0.1524)
				)
				(justify mirror)
			)
		)
		(property "Device Type" "C1206H71"
			(at -0.0127 -4.9911 180)
			(unlocked yes)
			(layer "B.Fab")
			(hide yes)
			(effects
				(font
					(size 1.016 1.016)
					(thickness 0.1524)
				)
				(justify mirror)
			)
		)
		(duplicate_pad_numbers_are_jumpers no)
		(fp_rect
			(start 1.0541 1.9812)
			(end -1.0541 -1.9812)
			(stroke
				(width 0)
				(type default)
			)
			(fill no)
			(layer "B.CrtYd")
		)
		(fp_rect
			(start 1.0541 1.9812)
			(end -1.0541 -1.9812)
			(stroke
				(width 0)
				(type default)
			)
			(fill no)
			(layer "B.Fab")
		)
		(pad "1" smd rect
			(at 0 -1.3462)
			(size 1.8542 1.016)
			(layers "B.Cu" "B.Mask" "B.Paste")
			(net "VDDR_5VBIAS")
		)
		(pad "2" smd rect
			(at 0 1.3462)
			(size 1.8542 1.016)
			(layers "B.Cu" "B.Mask" "B.Paste")
			(net "GND")
		)
	)
)
